# T6G (Grand Teton) — schematic netlist excerpt (pin names and nets, part order shuffled) for the footprints in the layout excerpt that follows; sources: Cadence DE-HDL packaged netlist, KiCad conversion of 04192023_DAF0TMB3IC0_F0TG_MB_C_brd_V02_OCP.brd

C6013  Q_CAP  0.1UF 25V 10% X7R  pkg 0402  page 180 : A = USB3_CPU0_BMC_TX_DP ; B = USB3_CPU0_BMC_TX_C2_DP

(kicad_pcb
	(version 20260206)
	(generator "pcbnew")
	(generator_version "10.0")
	(general
		(thickness 1.6)
		(legacy_teardrops no)
	)
	(paper "A4")
	(title_block
		(title "04192023_DAF0TMB3IC0_F0TG_MB_C_brd_V02_OCP.brd")
		(comment 1 "Grand Teton / footprints 4921-4921 of 8354")
	)
	(layers
		(0 "F.Cu" signal "TOP")
		(4 "In1.Cu" signal "GND")
		(6 "In2.Cu" signal "IN1")
		(8 "In3.Cu" signal "GND1")
		(10 "In4.Cu" signal "IN2")
		(12 "In5.Cu" signal "GND2")
		(14 "In6.Cu" signal "IN3")
		(16 "In7.Cu" signal "GND3")
		(18 "In8.Cu" signal "VCC")
		(20 "In9.Cu" signal "VCC1")
		(22 "In10.Cu" signal "GND4")
		(24 "In11.Cu" signal "IN4")
		(26 "In12.Cu" signal "GND5")
		(28 "In13.Cu" signal "IN5")
		(30 "In14.Cu" signal "GND6")
		(32 "In15.Cu" signal "IN6")
		(34 "In16.Cu" signal "GND7")
		(2 "B.Cu" signal "BOTTOM")
		(9 "F.Adhes" user "F.Adhesive")
		(11 "B.Adhes" user "B.Adhesive")
		(13 "F.Paste" user "Package Geometry/Pastemask Top")
		(15 "B.Paste" user "Package Geometry/Pastemask Bottom")
		(5 "F.SilkS" user "Ref Des/Silkscreen Top")
		(7 "B.SilkS" user "Ref Des/Silkscreen Bottom")
		(1 "F.Mask" user "Board Geometry/Soldermask Top")
		(3 "B.Mask" user "Board Geometry/Soldermask Bottom")
		(17 "Dwgs.User" user "User.Drawings")
		(19 "Cmts.User" user "User.Comments")
		(21 "Eco1.User" user "User.Eco1")
		(23 "Eco2.User" user "User.Eco2")
		(25 "Edge.Cuts" user "Board Geometry/Outline")
		(27 "Margin" user)
		(31 "F.CrtYd" user "Package Geometry/Place Bound Top")
		(29 "B.CrtYd" user "Package Geometry/Place Bound Bottom")
		(35 "F.Fab" user "Ref Des/Assembly Top")
		(33 "B.Fab" user "Ref Des/Assembly Bottom")
	)
	(footprint ""
		(layer "F.Cu")
		(at 145.63344 -30.78734 -90)
		(property "Reference" "C6013"
			(at 0 0 270)
			(layer "F.SilkS")
			(hide yes)
			(effects
				(font
					(size 1.27 1.27)
				)
			)
		)
		(property "Value" ""
			(at 0 0 270)
			(layer "F.Fab")
			(effects
				(font
					(size 1.27 1.27)
				)
			)
		)
		(duplicate_pad_numbers_are_jumpers no)
		(fp_line
			(start -0.7874 0.4064)
			(end -0.7874 -0.4064)
			(stroke
				(width 0.1524)
				(type default)
			)
			(layer "F.SilkS")
		)
		(fp_line
			(start 0.7874 0.4064)
			(end -0.7874 0.4064)
			(stroke
				(width 0.1524)
				(type default)
			)
			(layer "F.SilkS")
		)
		(fp_line
			(start -0.7874 -0.4064)
			(end 0.7874 -0.4064)
			(stroke
				(width 0.1524)
				(type default)
			)
			(layer "F.SilkS")
		)
		(fp_line
			(start 0.7874 -0.4064)
			(end 0.7874 0.4064)
			(stroke
				(width 0.1524)
				(type default)
			)
			(layer "F.SilkS")
		)
		(fp_line
			(start -0.6858 0.3048)
			(end -0.6858 -0.3048)
			(stroke
				(width 0.1)
				(type default)
			)
			(layer "F.Fab")
		)
		(fp_line
			(start -0.1016 0.3048)
			(end -0.6858 0.3048)
			(stroke
				(width 0.1)
				(type default)
			)
			(layer "F.Fab")
		)
		(fp_line
			(start 0.1016 0.3048)
			(end 0.1016 0.2794)
			(stroke
				(width 0.1)
				(type default)
			)
			(layer "F.Fab")
		)
		(fp_line
			(start 0.6858 0.3048)
			(end 0.1016 0.3048)
			(stroke
				(width 0.1)
				(type default)
			)
			(layer "F.Fab")
		)
		(fp_line
			(start -0.1016 0.2794)
			(end -0.1016 0.3048)
			(stroke
				(width 0.1)
				(type default)
			)
			(layer "F.Fab")
		)
		(fp_line
			(start 0.1016 0.2794)
			(end -0.1016 0.2794)
			(stroke
				(width 0.1)
				(type default)
			)
			(layer "F.Fab")
		)
		(fp_line
			(start -0.1016 -0.2794)
			(end 0.1016 -0.2794)
			(stroke
				(width 0.1)
				(type default)
			)
			(layer "F.Fab")
		)
		(fp_line
			(start 0.1016 -0.2794)
			(end 0.1016 -0.3048)
			(stroke
				(width 0.1)
				(type default)
			)
			(layer "F.Fab")
		)
		(fp_line
			(start -0.6858 -0.3048)
			(end -0.1016 -0.3048)
			(stroke
				(width 0.1)
				(type default)
			)
			(layer "F.Fab")
		)
		(fp_line
			(start -0.1016 -0.3048)
			(end -0.1016 -0.2794)
			(stroke
				(width 0.1)
				(type default)
			)
			(layer "F.Fab")
		)
		(fp_line
			(start 0.1016 -0.3048)
			(end 0.6858 -0.3048)
			(stroke
				(width 0.1)
				(type default)
			)
			(layer "F.Fab")
		)
		(fp_line
			(start 0.6858 -0.3048)
			(end 0.6858 0.3048)
			(stroke
				(width 0.1)
				(type default)
			)
			(layer "F.Fab")
		)
		(pad "1" smd rect
			(at -0.40005 0 90)
			(size 0.4572 0.508)
			(layers "F.Cu" "F.Mask" "F.Paste")
			(net "USB3_CPU0_BMC_TX_DP")
		)
		(pad "2" smd rect
			(at 0.40005 0 90)
			(size 0.4572 0.508)
			(layers "F.Cu" "F.Mask" "F.Paste")
			(net "USB3_CPU0_BMC_TX_C2_DP")
		)
	)
)
